(kicad_pcb
	(version 20260206)
	(generator "pcbnew")
	(generator_version "10.0")
	(general
		(thickness 1.6)
		(legacy_teardrops no)
	)
	(paper "A4")
	(title_block
		(title "01162023_DA0F0TEBIF0_F0T_Expander_BD_F_brd_V02_OCP.brd")
		(comment 1 "Grand Teton / footprints 307-312 of 9728")
	)
	(layers
		(0 "F.Cu" signal "TOP")
		(4 "In1.Cu" signal "GND")
		(6 "In2.Cu" signal "VCC")
		(8 "In3.Cu" signal "VCC1")
		(10 "In4.Cu" signal "GND1")
		(12 "In5.Cu" signal "IN1")
		(14 "In6.Cu" signal "GND2")
		(16 "In7.Cu" signal "IN2")
		(18 "In8.Cu" signal "GND3")
		(20 "In9.Cu" signal "IN3")
		(22 "In10.Cu" signal "GND4")
		(24 "In11.Cu" signal "IN4")
		(26 "In12.Cu" signal "GND5")
		(28 "In13.Cu" signal "IN5")
		(30 "In14.Cu" signal "GND6")
		(32 "In15.Cu" signal "IN6")
		(34 "In16.Cu" signal "GND7")
		(2 "B.Cu" signal "BOTTOM")
		(9 "F.Adhes" user "F.Adhesive")
		(11 "B.Adhes" user "B.Adhesive")
		(13 "F.Paste" user "Package Geometry/Pastemask Top")
		(15 "B.Paste" user "Package Geometry/Pastemask Bottom")
		(5 "F.SilkS" user "Ref Des/Silkscreen Top")
		(7 "B.SilkS" user "Ref Des/Silkscreen Bottom")
		(1 "F.Mask" user "Board Geometry/Soldermask Top")
		(3 "B.Mask" user "Board Geometry/Soldermask Bottom")
		(17 "Dwgs.User" user "User.Drawings")
		(19 "Cmts.User" user "User.Comments")
		(21 "Eco1.User" user "User.Eco1")
		(23 "Eco2.User" user "User.Eco2")
		(25 "Edge.Cuts" user "Board Geometry/Outline")
		(27 "Margin" user)
		(31 "F.CrtYd" user "Package Geometry/Place Bound Top")
		(29 "B.CrtYd" user "Package Geometry/Place Bound Bottom")
		(35 "F.Fab" user "Ref Des/Assembly Top")
		(33 "B.Fab" user "Ref Des/Assembly Bottom")
	)
	(footprint ""
		(layer "F.Cu")
		(at 168.684194 -29.222954 -90)
		(property "Reference" "PC928"
			(at 0 0 270)
			(layer "F.SilkS")
			(hide yes)
			(effects
				(font
					(size 1.27 1.27)
				)
			)
		)
		(property "Value" ""
			(at 0 0 270)
			(layer "F.Fab")
			(effects
				(font
					(size 1.27 1.27)
				)
			)
		)
		(duplicate_pad_numbers_are_jumpers no)
		(fp_line
			(start -0.7874 0.4064)
			(end -0.7874 -0.4064)
			(stroke
				(width 0.1524)
				(type default)
			)
			(layer "F.SilkS")
		)
		(fp_line
			(start 0.7874 0.4064)
			(end -0.7874 0.4064)
			(stroke
				(width 0.1524)
				(type default)
			)
			(layer "F.SilkS")
		)
		(fp_line
			(start -0.7874 -0.4064)
			(end 0.7874 -0.4064)
			(stroke
				(width 0.1524)
				(type default)
			)
			(layer "F.SilkS")
		)
		(fp_line
			(start 0.7874 -0.4064)
			(end 0.7874 0.4064)
			(stroke
				(width 0.1524)
				(type default)
			)
			(layer "F.SilkS")
		)
		(fp_line
			(start -0.67945 0.3048)
			(end -0.67945 -0.305054)
			(stroke
				(width 0.1)
				(type default)
			)
			(layer "F.Fab")
		)
		(fp_line
			(start -0.12065 0.3048)
			(end -0.67945 0.3048)
			(stroke
				(width 0.1)
				(type default)
			)
			(layer "F.Fab")
		)
		(fp_line
			(start 0.120396 0.3048)
			(end 0.120396 0.2794)
			(stroke
				(width 0.1)
				(type default)
			)
			(layer "F.Fab")
		)
		(fp_line
			(start 0.67945 0.3048)
			(end 0.120396 0.3048)
			(stroke
				(width 0.1)
				(type default)
			)
			(layer "F.Fab")
		)
		(fp_line
			(start -0.12065 0.2794)
			(end -0.12065 0.3048)
			(stroke
				(width 0.1)
				(type default)
			)
			(layer "F.Fab")
		)
		(fp_line
			(start 0.120396 0.2794)
			(end -0.12065 0.2794)
			(stroke
				(width 0.1)
				(type default)
			)
			(layer "F.Fab")
		)
		(fp_line
			(start -0.12065 -0.2794)
			(end 0.12065 -0.2794)
			(stroke
				(width 0.1)
				(type default)
			)
			(layer "F.Fab")
		)
		(fp_line
			(start 0.12065 -0.2794)
			(end 0.12065 -0.3048)
			(stroke
				(width 0.1)
				(type default)
			)
			(layer "F.Fab")
		)
		(fp_line
			(start 0.12065 -0.3048)
			(end 0.67945 -0.3048)
			(stroke
				(width 0.1)
				(type default)
			)
			(layer "F.Fab")
		)
		(fp_line
			(start 0.67945 -0.3048)
			(end 0.67945 0.3048)
			(stroke
				(width 0.1)
				(type default)
			)
			(layer "F.Fab")
		)
		(fp_line
			(start -0.67945 -0.305054)
			(end -0.12065 -0.305054)
			(stroke
				(width 0.1)
				(type default)
			)
			(layer "F.Fab")
		)
		(fp_line
			(start -0.12065 -0.305054)
			(end -0.12065 -0.2794)
			(stroke
				(width 0.1)
				(type default)
			)
			(layer "F.Fab")
		)
		(pad "1" smd circle
			(at -0.40005 0 270)
			(size 0 0)
			(layers "F.Cu" "F.Mask" "F.Paste")
			(net "P3V3_AUX")
		)
		(pad "2" smd circle
			(at 0.40005 0 270)
			(size 0 0)
			(layers "F.Cu" "F.Mask" "F.Paste")
			(net "GND")
		)
	)
	(footprint ""
		(layer "F.Cu")
		(at 363.474 -200.787 180)
		(property "Reference" "R4674"
			(at 0 0 180)
			(layer "F.SilkS")
			(hide yes)
			(effects
				(font
					(size 1.27 1.27)
				)
			)
		)
		(property "Value" ""
			(at 0 0 180)
			(layer "F.Fab")
			(effects
				(font
					(size 1.27 1.27)
				)
			)
		)
		(duplicate_pad_numbers_are_jumpers no)
		(fp_line
			(start 0.7874 0.4064)
			(end -0.7874 0.4064)
			(stroke
				(width 0.1524)
				(type default)
			)
			(layer "F.SilkS")
		)
		(fp_line
			(start 0.7874 -0.4064)
			(end 0.7874 0.4064)
			(stroke
				(width 0.1524)
				(type default)
			)
			(layer "F.SilkS")
		)
		(fp_line
			(start -0.7874 0.4064)
			(end -0.7874 -0.4064)
			(stroke
				(width 0.1524)
				(type default)
			)
			(layer "F.SilkS")
		)
		(fp_line
			(start -0.7874 -0.4064)
			(end 0.7874 -0.4064)
			(stroke
				(width 0.1524)
				(type default)
			)
			(layer "F.SilkS")
		)
		(fp_line
			(start 0.67945 0.3048)
			(end 0.120396 0.3048)
			(stroke
				(width 0.1)
				(type default)
			)
			(layer "F.Fab")
		)
		(fp_line
			(start 0.67945 -0.3048)
			(end 0.67945 0.3048)
			(stroke
				(width 0.1)
				(type default)
			)
			(layer "F.Fab")
		)
		(fp_line
			(start 0.12065 -0.2794)
			(end 0.12065 -0.3048)
			(stroke
				(width 0.1)
				(type default)
			)
			(layer "F.Fab")
		)
		(fp_line
			(start 0.12065 -0.3048)
			(end 0.67945 -0.3048)
			(stroke
				(width 0.1)
				(type default)
			)
			(layer "F.Fab")
		)
		(fp_line
			(start 0.120396 0.3048)
			(end 0.120396 0.2794)
			(stroke
				(width 0.1)
				(type default)
			)
			(layer "F.Fab")
		)
		(fp_line
			(start 0.120396 0.2794)
			(end -0.12065 0.2794)
			(stroke
				(width 0.1)
				(type default)
			)
			(layer "F.Fab")
		)
		(fp_line
			(start -0.12065 0.3048)
			(end -0.67945 0.3048)
			(stroke
				(width 0.1)
				(type default)
			)
			(layer "F.Fab")
		)
		(fp_line
			(start -0.12065 0.2794)
			(end -0.12065 0.3048)
			(stroke
				(width 0.1)
				(type default)
			)
			(layer "F.Fab")
		)
		(fp_line
			(start -0.12065 -0.2794)
			(end 0.12065 -0.2794)
			(stroke
				(width 0.1)
				(type default)
			)
			(layer "F.Fab")
		)
		(fp_line
			(start -0.12065 -0.305054)
			(end -0.12065 -0.2794)
			(stroke
				(width 0.1)
				(type default)
			)
			(layer "F.Fab")
		)
		(fp_line
			(start -0.67945 0.3048)
			(end -0.67945 -0.305054)
			(stroke
				(width 0.1)
				(type default)
			)
			(layer "F.Fab")
		)
		(fp_line
			(start -0.67945 -0.305054)
			(end -0.12065 -0.305054)
			(stroke
				(width 0.1)
				(type default)
			)
			(layer "F.Fab")
		)
		(pad "1" smd circle
			(at -0.40005 0 180)
			(size 0 0)
			(layers "F.Cu" "F.Mask" "F.Paste")
			(net "SSD4_PEX_PWR_EN_R")
		)
		(pad "2" smd circle
			(at 0.40005 0 180)
			(size 0 0)
			(layers "F.Cu" "F.Mask" "F.Paste")
			(net "GND")
		)
	)
	(footprint ""
		(layer "F.Cu")
		(at 291.194998 -101.782372 180)
		(property "Reference" "R276"
			(at 0 0 180)
			(layer "F.SilkS")
			(hide yes)
			(effects
				(font
					(size 1.27 1.27)
				)
			)
		)
		(property "Value" ""
			(at 0 0 180)
			(layer "F.Fab")
			(effects
				(font
					(size 1.27 1.27)
				)
			)
		)
		(duplicate_pad_numbers_are_jumpers no)
		(fp_line
			(start 0.7874 0.4064)
			(end -0.7874 0.4064)
			(stroke
				(width 0.1524)
				(type default)
			)
			(layer "F.SilkS")
		)
		(fp_line
			(start 0.7874 -0.4064)
			(end 0.7874 0.4064)
			(stroke
				(width 0.1524)
				(type default)
			)
			(layer "F.SilkS")
		)
		(fp_line
			(start -0.7874 0.4064)
			(end -0.7874 -0.4064)
			(stroke
				(width 0.1524)
				(type default)
			)
			(layer "F.SilkS")
		)
		(fp_line
			(start -0.7874 -0.4064)
			(end 0.7874 -0.4064)
			(stroke
				(width 0.1524)
				(type default)
			)
			(layer "F.SilkS")
		)
		(fp_line
			(start 0.67945 0.3048)
			(end 0.120396 0.3048)
			(stroke
				(width 0.1)
				(type default)
			)
			(layer "F.Fab")
		)
		(fp_line
			(start 0.67945 -0.3048)
			(end 0.67945 0.3048)
			(stroke
				(width 0.1)
				(type default)
			)
			(layer "F.Fab")
		)
		(fp_line
			(start 0.12065 -0.2794)
			(end 0.12065 -0.3048)
			(stroke
				(width 0.1)
				(type default)
			)
			(layer "F.Fab")
		)
		(fp_line
			(start 0.12065 -0.3048)
			(end 0.67945 -0.3048)
			(stroke
				(width 0.1)
				(type default)
			)
			(layer "F.Fab")
		)
		(fp_line
			(start 0.120396 0.3048)
			(end 0.120396 0.2794)
			(stroke
				(width 0.1)
				(type default)
			)
			(layer "F.Fab")
		)
		(fp_line
			(start 0.120396 0.2794)
			(end -0.12065 0.2794)
			(stroke
				(width 0.1)
				(type default)
			)
			(layer "F.Fab")
		)
		(fp_line
			(start -0.12065 0.3048)
			(end -0.67945 0.3048)
			(stroke
				(width 0.1)
				(type default)
			)
			(layer "F.Fab")
		)
		(fp_line
			(start -0.12065 0.2794)
			(end -0.12065 0.3048)
			(stroke
				(width 0.1)
				(type default)
			)
			(layer "F.Fab")
		)
		(fp_line
			(start -0.12065 -0.2794)
			(end 0.12065 -0.2794)
			(stroke
				(width 0.1)
				(type default)
			)
			(layer "F.Fab")
		)
		(fp_line
			(start -0.12065 -0.305054)
			(end -0.12065 -0.2794)
			(stroke
				(width 0.1)
				(type default)
			)
			(layer "F.Fab")
		)
		(fp_line
			(start -0.67945 0.3048)
			(end -0.67945 -0.305054)
			(stroke
				(width 0.1)
				(type default)
			)
			(layer "F.Fab")
		)
		(fp_line
			(start -0.67945 -0.305054)
			(end -0.12065 -0.305054)
			(stroke
				(width 0.1)
				(type default)
			)
			(layer "F.Fab")
		)
		(pad "1" smd circle
			(at -0.40005 0 180)
			(size 0 0)
			(layers "F.Cu" "F.Mask" "F.Paste")
			(net "NCSI_NIC5_TX_EN")
		)
		(pad "2" smd circle
			(at 0.40005 0 180)
			(size 0 0)
			(layers "F.Cu" "F.Mask" "F.Paste")
			(net "GND")
		)
	)
	(footprint ""
		(layer "F.Cu")
		(at 228.578664 -204.44206 -90)
		(property "Reference" "R5296"
			(at 0 0 270)
			(layer "F.SilkS")
			(hide yes)
			(effects
				(font
					(size 1.27 1.27)
				)
			)
		)
		(property "Value" ""
			(at 0 0 270)
			(layer "F.Fab")
			(effects
				(font
					(size 1.27 1.27)
				)
			)
		)
		(duplicate_pad_numbers_are_jumpers no)
		(fp_line
			(start -0.7874 0.4064)
			(end -0.7874 -0.4064)
			(stroke
				(width 0.1524)
				(type default)
			)
			(layer "F.SilkS")
		)
		(fp_line
			(start 0.7874 0.4064)
			(end -0.7874 0.4064)
			(stroke
				(width 0.1524)
				(type default)
			)
			(layer "F.SilkS")
		)
		(fp_line
			(start -0.7874 -0.4064)
			(end 0.7874 -0.4064)
			(stroke
				(width 0.1524)
				(type default)
			)
			(layer "F.SilkS")
		)
		(fp_line
			(start 0.7874 -0.4064)
			(end 0.7874 0.4064)
			(stroke
				(width 0.1524)
				(type default)
			)
			(layer "F.SilkS")
		)
		(fp_line
			(start -0.67945 0.3048)
			(end -0.67945 -0.305054)
			(stroke
				(width 0.1)
				(type default)
			)
			(layer "F.Fab")
		)
		(fp_line
			(start -0.12065 0.3048)
			(end -0.67945 0.3048)
			(stroke
				(width 0.1)
				(type default)
			)
			(layer "F.Fab")
		)
		(fp_line
			(start 0.120396 0.3048)
			(end 0.120396 0.2794)
			(stroke
				(width 0.1)
				(type default)
			)
			(layer "F.Fab")
		)
		(fp_line
			(start 0.67945 0.3048)
			(end 0.120396 0.3048)
			(stroke
				(width 0.1)
				(type default)
			)
			(layer "F.Fab")
		)
		(fp_line
			(start -0.12065 0.2794)
			(end -0.12065 0.3048)
			(stroke
				(width 0.1)
				(type default)
			)
			(layer "F.Fab")
		)
		(fp_line
			(start 0.120396 0.2794)
			(end -0.12065 0.2794)
			(stroke
				(width 0.1)
				(type default)
			)
			(layer "F.Fab")
		)
		(fp_line
			(start -0.12065 -0.2794)
			(end 0.12065 -0.2794)
			(stroke
				(width 0.1)
				(type default)
			)
			(layer "F.Fab")
		)
		(fp_line
			(start 0.12065 -0.2794)
			(end 0.12065 -0.3048)
			(stroke
				(width 0.1)
				(type default)
			)
			(layer "F.Fab")
		)
		(fp_line
			(start 0.12065 -0.3048)
			(end 0.67945 -0.3048)
			(stroke
				(width 0.1)
				(type default)
			)
			(layer "F.Fab")
		)
		(fp_line
			(start 0.67945 -0.3048)
			(end 0.67945 0.3048)
			(stroke
				(width 0.1)
				(type default)
			)
			(layer "F.Fab")
		)
		(fp_line
			(start -0.67945 -0.305054)
			(end -0.12065 -0.305054)
			(stroke
				(width 0.1)
				(type default)
			)
			(layer "F.Fab")
		)
		(fp_line
			(start -0.12065 -0.305054)
			(end -0.12065 -0.2794)
			(stroke
				(width 0.1)
				(type default)
			)
			(layer "F.Fab")
		)
		(pad "1" smd circle
			(at -0.40005 0 270)
			(size 0 0)
			(layers "F.Cu" "F.Mask" "F.Paste")
			(net "BIC_SEL_FLASH_SW3")
		)
		(pad "2" smd circle
			(at 0.40005 0 270)
			(size 0 0)
			(layers "F.Cu" "F.Mask" "F.Paste")
			(net "BIC_SEL_FLASH_SW3_R")
		)
	)
	(footprint ""
		(layer "F.Cu")
		(at 339.752686 -93.11894 -90)
		(property "Reference" "R1184"
			(at 0 0 270)
			(layer "F.SilkS")
			(hide yes)
			(effects
				(font
					(size 1.27 1.27)
				)
			)
		)
		(property "Value" ""
			(at 0 0 270)
			(layer "F.Fab")
			(effects
				(font
					(size 1.27 1.27)
				)
			)
		)
		(duplicate_pad_numbers_are_jumpers no)
		(fp_line
			(start -0.7874 -0.4064)
			(end 0.7874 -0.4064)
			(stroke
				(width 0.1524)
				(type default)
			)
			(layer "F.SilkS")
		)
		(fp_line
			(start -0.67945 0.3048)
			(end -0.67945 -0.305054)
			(stroke
				(width 0.1)
				(type default)
			)
			(layer "F.Fab")
		)
		(fp_line
			(start -0.12065 0.3048)
			(end -0.67945 0.3048)
			(stroke
				(width 0.1)
				(type default)
			)
			(layer "F.Fab")
		)
		(fp_line
			(start 0.120396 0.3048)
			(end 0.120396 0.2794)
			(stroke
				(width 0.1)
				(type default)
			)
			(layer "F.Fab")
		)
		(fp_line
			(start 0.67945 0.3048)
			(end 0.120396 0.3048)
			(stroke
				(width 0.1)
				(type default)
			)
			(layer "F.Fab")
		)
		(fp_line
			(start -0.12065 0.2794)
			(end -0.12065 0.3048)
			(stroke
				(width 0.1)
				(type default)
			)
			(layer "F.Fab")
		)
		(fp_line
			(start 0.120396 0.2794)
			(end -0.12065 0.2794)
			(stroke
				(width 0.1)
				(type default)
			)
			(layer "F.Fab")
		)
		(fp_line
			(start -0.12065 -0.2794)
			(end 0.12065 -0.2794)
			(stroke
				(width 0.1)
				(type default)
			)
			(layer "F.Fab")
		)
		(fp_line
			(start 0.12065 -0.2794)
			(end 0.12065 -0.3048)
			(stroke
				(width 0.1)
				(type default)
			)
			(layer "F.Fab")
		)
		(fp_line
			(start 0.12065 -0.3048)
			(end 0.67945 -0.3048)
			(stroke
				(width 0.1)
				(type default)
			)
			(layer "F.Fab")
		)
		(fp_line
			(start 0.67945 -0.3048)
			(end 0.67945 0.3048)
			(stroke
				(width 0.1)
				(type default)
			)
			(layer "F.Fab")
		)
		(fp_line
			(start -0.67945 -0.305054)
			(end -0.12065 -0.305054)
			(stroke
				(width 0.1)
				(type default)
			)
			(layer "F.Fab")
		)
		(fp_line
			(start -0.12065 -0.305054)
			(end -0.12065 -0.2794)
			(stroke
				(width 0.1)
				(type default)
			)
			(layer "F.Fab")
		)
		(pad "1" smd circle
			(at -0.40005 0 270)
			(size 0 0)
			(layers "F.Cu" "F.Mask" "F.Paste")
			(net "CLK_100M_DB800ZL_SSD15_R_DP")
		)
		(pad "2" smd circle
			(at 0.40005 0 270)
			(size 0 0)
			(layers "F.Cu" "F.Mask" "F.Paste")
			(net "CLK_100M_DB800ZL_SSD15_DP")
		)
	)
	(footprint ""
		(layer "F.Cu")
		(at 59.799982 -407.960068 180)
		(property "Reference" "J63"
			(at 0.047498 -11.476228 0)
			(unlocked yes)
			(layer "F.SilkS")
			(effects
				(font
					(size 0.7874 0.5842)
					(thickness 0.1524)
				)
			)
		)
		(property "Value" ""
			(at 0 0 180)
			(layer "F.Fab")
			(effects
				(font
					(size 1.27 1.27)
				)
			)
		)
		(duplicate_pad_numbers_are_jumpers no)
		(fp_line
			(start 3.525012 21.310092)
			(end 3.525012 -10.489946)
			(stroke
				(width 0.1524)
				(type default)
			)
			(layer "F.SilkS")
		)
		(fp_line
			(start 3.525012 -10.489946)
			(end -3.525012 -10.489946)
			(stroke
				(width 0.1524)
				(type default)
			)
			(layer "F.SilkS")
		)
		(fp_line
			(start -3.525012 21.310092)
			(end 3.525012 21.310092)
			(stroke
				(width 0.1524)
				(type default)
			)
			(layer "F.SilkS")
		)
		(fp_line
			(start -3.525012 10.6299)
			(end 3.525012 10.6299)
			(stroke
				(width 0.1524)
				(type default)
			)
			(layer "F.SilkS")
		)
		(fp_line
			(start -3.525012 -10.489946)
			(end -3.525012 21.310092)
			(stroke
				(width 0.1524)
				(type default)
			)
			(layer "F.SilkS")
		)
		(fp_line
			(start 3.525012 21.310092)
			(end 3.525012 -10.489946)
			(stroke
				(width 0.1)
				(type default)
			)
			(layer "F.Fab")
		)
		(fp_line
			(start 3.525012 -10.489946)
			(end -3.525012 -10.489946)
			(stroke
				(width 0.1)
				(type default)
			)
			(layer "F.Fab")
		)
		(fp_line
			(start -3.525012 21.310092)
			(end 3.525012 21.310092)
			(stroke
				(width 0.1)
				(type default)
			)
			(layer "F.Fab")
		)
		(fp_line
			(start -3.525012 -10.489946)
			(end -3.525012 21.310092)
			(stroke
				(width 0.1)
				(type default)
			)
			(layer "F.Fab")
		)
		(pad "" np_thru_hole circle
			(at 0 -6.620002 180)
			(size 3.175 3.175)
			(drill 3.175)
			(layers "*.Cu" "*.Mask")
			(clearance 0.381)
			(thermal_gap 0.381)
		)
		(pad "" np_thru_hole circle
			(at 0 0 180)
			(size 0 0)
			(drill 3.175)
			(layers "*.Cu" "*.Mask")
			(clearance 0)
		)
		(pad "" np_thru_hole circle
			(at 0 5.130038 180)
			(size 3.175 3.175)
			(drill 3.175)
			(layers "*.Cu" "*.Mask")
			(clearance 0.381)
			(thermal_gap 0.381)
		)
		(zone
			(layers "F.Cu" "B.Cu" "In1.Cu" "In2.Cu" "In3.Cu" "In4.Cu" "In5.Cu" "In6.Cu"
				"In7.Cu" "In8.Cu" "In9.Cu" "In10.Cu" "In11.Cu" "In12.Cu" "In13.Cu" "In14.Cu"
				"In15.Cu" "In16.Cu"
			)
			(hatch none 0.5)
			(connect_pads
				(clearance 0)
			)
			(min_thickness 0.25)
			(keepout
				(tracks not_allowed)
				(vias allowed)
				(pads allowed)
				(copperpour not_allowed)
				(footprints allowed)
			)
			(placement
				(enabled no)
				(sheetname "")
			)
			(fill
				(thermal_gap 0.5)
				(thermal_bridge_width 0.5)
				(island_removal_mode 0)
			)
			(polygon
				(pts
					(arc
						(start 61.895482 -413.090106)
						(mid 57.704482 -413.090106)
						(end 61.895482 -413.090106)
					)
				)
			)
		)
		(zone
			(layers "F.Cu" "B.Cu" "In1.Cu" "In2.Cu" "In3.Cu" "In4.Cu" "In5.Cu" "In6.Cu"
				"In7.Cu" "In8.Cu" "In9.Cu" "In10.Cu" "In11.Cu" "In12.Cu" "In13.Cu" "In14.Cu"
				"In15.Cu" "In16.Cu"
			)
			(hatch none 0.5)
			(connect_pads
				(clearance 0)
			)
			(min_thickness 0.25)
			(keepout
				(tracks not_allowed)
				(vias allowed)
				(pads allowed)
				(copperpour not_allowed)
				(footprints allowed)
			)
			(placement
				(enabled no)
				(sheetname "")
			)
			(fill
				(thermal_gap 0.5)
				(thermal_bridge_width 0.5)
				(island_removal_mode 0)
			)
			(polygon
				(pts
					(arc
						(start 61.895482 -401.340066)
						(mid 57.704482 -401.340066)
						(end 61.895482 -401.340066)
					)
				)
			)
		)
		(zone
			(layers "F.Cu" "B.Cu" "In1.Cu" "In2.Cu" "In3.Cu" "In4.Cu" "In5.Cu" "In6.Cu"
				"In7.Cu" "In8.Cu" "In9.Cu" "In10.Cu" "In11.Cu" "In12.Cu" "In13.Cu" "In14.Cu"
				"In15.Cu" "In16.Cu"
			)
			(hatch none 0.5)
			(connect_pads
				(clearance 0)
			)
			(min_thickness 0.25)
			(keepout
				(tracks not_allowed)
				(vias allowed)
				(pads allowed)
				(copperpour not_allowed)
				(footprints allowed)
			)
			(placement
				(enabled no)
				(sheetname "")
			)
			(fill
				(thermal_gap 0.5)
				(thermal_bridge_width 0.5)
				(island_removal_mode 0)
			)
			(polygon
				(pts
					(arc
						(start 63.419482 -407.960068)
						(mid 56.180482 -407.960068)
						(end 63.419482 -407.960068)
					)
				)
			)
		)
	)
)
